(kicad_pcb
	(version 20260206)
	(generator "pcbnew")
	(generator_version "10.0")
	(general
		(thickness 1.6)
		(legacy_teardrops no)
	)
	(paper "A4")
	(title_block
		(title "01162023_DA0F0TEBIF0_F0T_Expander_BD_F_brd_V02_OCP.brd")
		(comment 1 "Grand Teton / footprints 8235-8242 of 9728")
	)
	(layers
		(0 "F.Cu" signal "TOP")
		(4 "In1.Cu" signal "GND")
		(6 "In2.Cu" signal "VCC")
		(8 "In3.Cu" signal "VCC1")
		(10 "In4.Cu" signal "GND1")
		(12 "In5.Cu" signal "IN1")
		(14 "In6.Cu" signal "GND2")
		(16 "In7.Cu" signal "IN2")
		(18 "In8.Cu" signal "GND3")
		(20 "In9.Cu" signal "IN3")
		(22 "In10.Cu" signal "GND4")
		(24 "In11.Cu" signal "IN4")
		(26 "In12.Cu" signal "GND5")
		(28 "In13.Cu" signal "IN5")
		(30 "In14.Cu" signal "GND6")
		(32 "In15.Cu" signal "IN6")
		(34 "In16.Cu" signal "GND7")
		(2 "B.Cu" signal "BOTTOM")
		(9 "F.Adhes" user "F.Adhesive")
		(11 "B.Adhes" user "B.Adhesive")
		(13 "F.Paste" user "Package Geometry/Pastemask Top")
		(15 "B.Paste" user "Package Geometry/Pastemask Bottom")
		(5 "F.SilkS" user "Ref Des/Silkscreen Top")
		(7 "B.SilkS" user "Ref Des/Silkscreen Bottom")
		(1 "F.Mask" user "Board Geometry/Soldermask Top")
		(3 "B.Mask" user "Board Geometry/Soldermask Bottom")
		(17 "Dwgs.User" user "User.Drawings")
		(19 "Cmts.User" user "User.Comments")
		(21 "Eco1.User" user "User.Eco1")
		(23 "Eco2.User" user "User.Eco2")
		(25 "Edge.Cuts" user "Board Geometry/Outline")
		(27 "Margin" user)
		(31 "F.CrtYd" user "Package Geometry/Place Bound Top")
		(29 "B.CrtYd" user "Package Geometry/Place Bound Bottom")
		(35 "F.Fab" user "Ref Des/Assembly Top")
		(33 "B.Fab" user "Ref Des/Assembly Bottom")
	)
	(footprint ""
		(layer "B.Cu")
		(at 239.209072 -220.085412 90)
		(property "Reference" "C3618"
			(at 0 0 90)
			(layer "B.SilkS")
			(hide yes)
			(effects
				(font
					(size 1.27 1.27)
				)
				(justify mirror)
			)
		)
		(property "Value" ""
			(at 0 0 90)
			(layer "B.Fab")
			(effects
				(font
					(size 1.27 1.27)
				)
				(justify mirror)
			)
		)
		(duplicate_pad_numbers_are_jumpers no)
		(fp_line
			(start 0.69215 -0.2921)
			(end -0.69215 -0.2921)
			(stroke
				(width 0.1524)
				(type default)
			)
			(layer "B.SilkS")
		)
		(fp_line
			(start -0.69215 -0.2921)
			(end -0.69215 0.2921)
			(stroke
				(width 0.1524)
				(type default)
			)
			(layer "B.SilkS")
		)
		(fp_line
			(start 0.69215 0.2921)
			(end 0.69215 -0.2921)
			(stroke
				(width 0.1524)
				(type default)
			)
			(layer "B.SilkS")
		)
		(fp_line
			(start -0.69215 0.2921)
			(end 0.69215 0.2921)
			(stroke
				(width 0.1524)
				(type default)
			)
			(layer "B.SilkS")
		)
		(fp_line
			(start 0.51435 -0.2794)
			(end -0.51435 -0.2794)
			(stroke
				(width 0.1)
				(type default)
			)
			(layer "B.Fab")
		)
		(fp_line
			(start -0.51435 -0.2794)
			(end -0.51435 0.2794)
			(stroke
				(width 0.1)
				(type default)
			)
			(layer "B.Fab")
		)
		(fp_line
			(start 0.51435 0.2794)
			(end 0.51435 -0.2794)
			(stroke
				(width 0.1)
				(type default)
			)
			(layer "B.Fab")
		)
		(fp_line
			(start -0.51435 0.2794)
			(end 0.51435 0.2794)
			(stroke
				(width 0.1)
				(type default)
			)
			(layer "B.Fab")
		)
		(pad "1" smd circle
			(at 0.40005 0 270)
			(size 0 0)
			(layers "B.Cu" "B.Mask" "B.Paste")
			(net "BIC_ADCVREFP1")
		)
		(pad "2" smd circle
			(at -0.40005 0 270)
			(size 0 0)
			(layers "B.Cu" "B.Mask" "B.Paste")
			(net "BIC_ADCVREFN1")
		)
		(zone
			(layer "B.Cu")
			(hatch none 0.5)
			(connect_pads
				(clearance 0)
			)
			(min_thickness 0.25)
			(keepout
				(tracks not_allowed)
				(vias allowed)
				(pads allowed)
				(copperpour not_allowed)
				(footprints allowed)
			)
			(placement
				(enabled no)
				(sheetname "")
			)
			(fill
				(thermal_gap 0.5)
				(thermal_bridge_width 0.5)
				(island_removal_mode 0)
			)
			(polygon
				(pts
					(xy 239.296702 -220.275912) (xy 239.354868 -220.184472) (xy 239.354868 -219.985082) (xy 239.296702 -219.894912)
					(xy 239.121442 -219.894912) (xy 239.063022 -219.985082) (xy 239.063022 -220.184472) (xy 239.121188 -220.275912)
				)
			)
		)
	)
	(footprint ""
		(layer "B.Cu")
		(at 400.77009 -305.399948 -90)
		(property "Reference" "C3492"
			(at 0 0 90)
			(layer "B.SilkS")
			(hide yes)
			(effects
				(font
					(size 1.27 1.27)
				)
				(justify mirror)
			)
		)
		(property "Value" ""
			(at 0 0 90)
			(layer "B.Fab")
			(effects
				(font
					(size 1.27 1.27)
				)
				(justify mirror)
			)
		)
		(duplicate_pad_numbers_are_jumpers no)
		(fp_line
			(start -0.299974 0.150114)
			(end 0.299974 0.150114)
			(stroke
				(width 0.1)
				(type default)
			)
			(layer "B.Fab")
		)
		(fp_line
			(start 0.299974 0.150114)
			(end 0.299974 -0.150114)
			(stroke
				(width 0.1)
				(type default)
			)
			(layer "B.Fab")
		)
		(fp_line
			(start -0.299974 -0.150114)
			(end -0.299974 0.150114)
			(stroke
				(width 0.1)
				(type default)
			)
			(layer "B.Fab")
		)
		(fp_line
			(start 0.299974 -0.150114)
			(end -0.299974 -0.150114)
			(stroke
				(width 0.1)
				(type default)
			)
			(layer "B.Fab")
		)
		(pad "1" smd rect
			(at 0.2667 0 90)
			(size 0.3048 0.381)
			(layers "B.Cu" "B.Mask" "B.Paste")
			(net "P1V25_SERDES_VDDPLL_PEX3")
		)
		(pad "2" smd rect
			(at -0.2667 0 90)
			(size 0.3048 0.381)
			(layers "B.Cu" "B.Mask" "B.Paste")
			(net "GND")
		)
	)
	(footprint ""
		(layer "B.Cu")
		(at 297.074844 -286.399732 90)
		(property "Reference" "C3328"
			(at 0 0 90)
			(layer "B.SilkS")
			(hide yes)
			(effects
				(font
					(size 1.27 1.27)
				)
				(justify mirror)
			)
		)
		(property "Value" ""
			(at 0 0 90)
			(layer "B.Fab")
			(effects
				(font
					(size 1.27 1.27)
				)
				(justify mirror)
			)
		)
		(duplicate_pad_numbers_are_jumpers no)
		(fp_line
			(start 0.299974 -0.150114)
			(end -0.299974 -0.150114)
			(stroke
				(width 0.1)
				(type default)
			)
			(layer "B.Fab")
		)
		(fp_line
			(start -0.299974 -0.150114)
			(end -0.299974 0.150114)
			(stroke
				(width 0.1)
				(type default)
			)
			(layer "B.Fab")
		)
		(fp_line
			(start 0.299974 0.150114)
			(end 0.299974 -0.150114)
			(stroke
				(width 0.1)
				(type default)
			)
			(layer "B.Fab")
		)
		(fp_line
			(start -0.299974 0.150114)
			(end 0.299974 0.150114)
			(stroke
				(width 0.1)
				(type default)
			)
			(layer "B.Fab")
		)
		(pad "1" smd rect
			(at 0.2667 0 270)
			(size 0.3048 0.381)
			(layers "B.Cu" "B.Mask" "B.Paste")
			(net "P1V25_SERDES_VDDPLL_PEX2")
		)
		(pad "2" smd rect
			(at -0.2667 0 270)
			(size 0.3048 0.381)
			(layers "B.Cu" "B.Mask" "B.Paste")
			(net "GND")
		)
	)
	(footprint ""
		(layer "B.Cu")
		(at 226.694492 -176.303178 180)
		(property "Reference" "U450"
			(at -1.600708 -1.755648 0)
			(unlocked yes)
			(layer "B.SilkS")
			(effects
				(font
					(size 0.7874 0.5842)
					(thickness 0.1524)
				)
				(justify left mirror)
			)
		)
		(property "Value" ""
			(at 0 0 0)
			(layer "B.Fab")
			(effects
				(font
					(size 1.27 1.27)
				)
				(justify mirror)
			)
		)
		(duplicate_pad_numbers_are_jumpers no)
		(fp_line
			(start 0.779018 0.800862)
			(end -0.779018 0.800862)
			(stroke
				(width 0.1524)
				(type default)
			)
			(layer "B.SilkS")
		)
		(fp_line
			(start 0.779018 -0.800862)
			(end 0.779018 0.800862)
			(stroke
				(width 0.1524)
				(type default)
			)
			(layer "B.SilkS")
		)
		(fp_line
			(start -0.779018 0.800862)
			(end -0.779018 -0.800862)
			(stroke
				(width 0.1524)
				(type default)
			)
			(layer "B.SilkS")
		)
		(fp_line
			(start -0.779018 -0.800862)
			(end 0.779018 -0.800862)
			(stroke
				(width 0.1524)
				(type default)
			)
			(layer "B.SilkS")
		)
		(fp_poly
			(pts
				(xy 0.923544 -0.500126) (xy 1.313434 -0.714502) (xy 1.313434 -0.285496)
			)
			(stroke
				(width 0)
				(type default)
			)
			(fill yes)
			(layer "B.SilkS")
		)
		(fp_line
			(start 0.525018 0.750062)
			(end 0.525018 -0.750062)
			(stroke
				(width 0.1)
				(type default)
			)
			(layer "B.Fab")
		)
		(fp_line
			(start 0.525018 -0.750062)
			(end -0.525018 -0.750062)
			(stroke
				(width 0.1)
				(type default)
			)
			(layer "B.Fab")
		)
		(fp_line
			(start -0.525018 0.750062)
			(end 0.525018 0.750062)
			(stroke
				(width 0.1)
				(type default)
			)
			(layer "B.Fab")
		)
		(fp_line
			(start -0.525018 -0.750062)
			(end -0.525018 0.750062)
			(stroke
				(width 0.1)
				(type default)
			)
			(layer "B.Fab")
		)
		(fp_poly
			(pts
				(xy 0.923544 -0.500126) (xy 1.313434 -0.714502) (xy 1.313434 -0.285496)
			)
			(stroke
				(width 0)
				(type default)
			)
			(fill yes)
			(layer "B.Fab")
		)
		(pad "1" smd rect
			(at 0.377444 -0.500126 90)
			(size 0.3048 0.5334)
			(layers "B.Cu" "B.Mask" "B.Paste")
			(net "ADM1085_CEXT")
		)
		(pad "2" smd rect
			(at 0.372618 0 90)
			(size 0.2794 0.508)
			(layers "B.Cu" "B.Mask" "B.Paste")
			(net "GND")
		)
		(pad "3" smd rect
			(at 0.372618 0.499872 90)
			(size 0.2794 0.508)
			(layers "B.Cu" "B.Mask" "B.Paste")
			(net "ADM1085_IN")
		)
		(pad "4" smd rect
			(at -0.377444 0.499872 90)
			(size 0.2794 0.508)
			(layers "B.Cu" "B.Mask" "B.Paste")
			(net "ADM1085_ENOUT")
		)
		(pad "5" smd rect
			(at -0.377444 0 90)
			(size 0.2794 0.508)
			(layers "B.Cu" "B.Mask" "B.Paste")
			(net "THRESHOLD")
		)
		(pad "6" smd rect
			(at -0.377444 -0.500126 90)
			(size 0.2794 0.508)
			(layers "B.Cu" "B.Mask" "B.Paste")
			(net "P3V3_AUX")
		)
	)
	(footprint ""
		(layer "B.Cu")
		(at 306.633626 -246.199406 90)
		(property "Reference" "R4104"
			(at 0 0 90)
			(layer "B.SilkS")
			(hide yes)
			(effects
				(font
					(size 1.27 1.27)
				)
				(justify mirror)
			)
		)
		(property "Value" ""
			(at 0 0 90)
			(layer "B.Fab")
			(effects
				(font
					(size 1.27 1.27)
				)
				(justify mirror)
			)
		)
		(duplicate_pad_numbers_are_jumpers no)
		(fp_line
			(start 0.7874 -0.4064)
			(end -0.7874 -0.4064)
			(stroke
				(width 0.1524)
				(type default)
			)
			(layer "B.SilkS")
		)
		(fp_line
			(start -0.7874 -0.4064)
			(end -0.7874 0.4064)
			(stroke
				(width 0.1524)
				(type default)
			)
			(layer "B.SilkS")
		)
		(fp_line
			(start 0.7874 0.4064)
			(end 0.7874 -0.4064)
			(stroke
				(width 0.1524)
				(type default)
			)
			(layer "B.SilkS")
		)
		(fp_line
			(start -0.7874 0.4064)
			(end 0.7874 0.4064)
			(stroke
				(width 0.1524)
				(type default)
			)
			(layer "B.SilkS")
		)
		(fp_line
			(start 0.67945 -0.305054)
			(end 0.12065 -0.305054)
			(stroke
				(width 0.1)
				(type default)
			)
			(layer "B.Fab")
		)
		(fp_line
			(start 0.12065 -0.305054)
			(end 0.12065 -0.2794)
			(stroke
				(width 0.1)
				(type default)
			)
			(layer "B.Fab")
		)
		(fp_line
			(start -0.12065 -0.3048)
			(end -0.67945 -0.3048)
			(stroke
				(width 0.1)
				(type default)
			)
			(layer "B.Fab")
		)
		(fp_line
			(start -0.67945 -0.3048)
			(end -0.67945 0.3048)
			(stroke
				(width 0.1)
				(type default)
			)
			(layer "B.Fab")
		)
		(fp_line
			(start 0.12065 -0.2794)
			(end -0.12065 -0.2794)
			(stroke
				(width 0.1)
				(type default)
			)
			(layer "B.Fab")
		)
		(fp_line
			(start -0.12065 -0.2794)
			(end -0.12065 -0.3048)
			(stroke
				(width 0.1)
				(type default)
			)
			(layer "B.Fab")
		)
		(fp_line
			(start 0.12065 0.2794)
			(end 0.12065 0.3048)
			(stroke
				(width 0.1)
				(type default)
			)
			(layer "B.Fab")
		)
		(fp_line
			(start -0.120396 0.2794)
			(end 0.12065 0.2794)
			(stroke
				(width 0.1)
				(type default)
			)
			(layer "B.Fab")
		)
		(fp_line
			(start 0.67945 0.3048)
			(end 0.67945 -0.305054)
			(stroke
				(width 0.1)
				(type default)
			)
			(layer "B.Fab")
		)
		(fp_line
			(start 0.12065 0.3048)
			(end 0.67945 0.3048)
			(stroke
				(width 0.1)
				(type default)
			)
			(layer "B.Fab")
		)
		(fp_line
			(start -0.120396 0.3048)
			(end -0.120396 0.2794)
			(stroke
				(width 0.1)
				(type default)
			)
			(layer "B.Fab")
		)
		(fp_line
			(start -0.67945 0.3048)
			(end -0.120396 0.3048)
			(stroke
				(width 0.1)
				(type default)
			)
			(layer "B.Fab")
		)
		(pad "1" smd circle
			(at 0.40005 0 270)
			(size 0 0)
			(layers "B.Cu" "B.Mask" "B.Paste")
			(net "SMB_MB_BMC_R_SCL")
		)
		(pad "2" smd circle
			(at -0.40005 0 270)
			(size 0 0)
			(layers "B.Cu" "B.Mask" "B.Paste")
			(net "SMB_MB_BMC_ISO_SCL")
		)
	)
	(footprint ""
		(layer "B.Cu")
		(at 185.250074 -303.024794)
		(property "Reference" "C3165"
			(at 0 0 0)
			(layer "B.SilkS")
			(hide yes)
			(effects
				(font
					(size 1.27 1.27)
				)
				(justify mirror)
			)
		)
		(property "Value" ""
			(at 0 0 0)
			(layer "B.Fab")
			(effects
				(font
					(size 1.27 1.27)
				)
				(justify mirror)
			)
		)
		(duplicate_pad_numbers_are_jumpers no)
		(fp_line
			(start -0.299974 -0.150114)
			(end -0.299974 0.150114)
			(stroke
				(width 0.1)
				(type default)
			)
			(layer "B.Fab")
		)
		(fp_line
			(start -0.299974 0.150114)
			(end 0.299974 0.150114)
			(stroke
				(width 0.1)
				(type default)
			)
			(layer "B.Fab")
		)
		(fp_line
			(start 0.299974 -0.150114)
			(end -0.299974 -0.150114)
			(stroke
				(width 0.1)
				(type default)
			)
			(layer "B.Fab")
		)
		(fp_line
			(start 0.299974 0.150114)
			(end 0.299974 -0.150114)
			(stroke
				(width 0.1)
				(type default)
			)
			(layer "B.Fab")
		)
		(pad "1" smd rect
			(at 0.2667 0 180)
			(size 0.3048 0.381)
			(layers "B.Cu" "B.Mask" "B.Paste")
			(net "P1V8_PEX")
		)
		(pad "2" smd rect
			(at -0.2667 0 180)
			(size 0.3048 0.381)
			(layers "B.Cu" "B.Mask" "B.Paste")
			(net "GND")
		)
	)
	(footprint ""
		(layer "B.Cu")
		(at 165.299898 -292.574726 180)
		(property "Reference" "C1361"
			(at 0 0 0)
			(layer "B.SilkS")
			(hide yes)
			(effects
				(font
					(size 1.27 1.27)
				)
				(justify mirror)
			)
		)
		(property "Value" ""
			(at 0 0 0)
			(layer "B.Fab")
			(effects
				(font
					(size 1.27 1.27)
				)
				(justify mirror)
			)
		)
		(duplicate_pad_numbers_are_jumpers no)
		(fp_line
			(start 0.299974 0.150114)
			(end 0.299974 -0.150114)
			(stroke
				(width 0.1)
				(type default)
			)
			(layer "B.Fab")
		)
		(fp_line
			(start 0.299974 -0.150114)
			(end -0.299974 -0.150114)
			(stroke
				(width 0.1)
				(type default)
			)
			(layer "B.Fab")
		)
		(fp_line
			(start -0.299974 0.150114)
			(end 0.299974 0.150114)
			(stroke
				(width 0.1)
				(type default)
			)
			(layer "B.Fab")
		)
		(fp_line
			(start -0.299974 -0.150114)
			(end -0.299974 0.150114)
			(stroke
				(width 0.1)
				(type default)
			)
			(layer "B.Fab")
		)
		(pad "1" smd rect
			(at 0.2667 0)
			(size 0.3048 0.381)
			(layers "B.Cu" "B.Mask" "B.Paste")
			(net "P0V8_PEX1")
		)
		(pad "2" smd rect
			(at -0.2667 0)
			(size 0.3048 0.381)
			(layers "B.Cu" "B.Mask" "B.Paste")
			(net "GND")
		)
	)
	(footprint ""
		(layer "B.Cu")
		(at 132.939536 -215.85682 180)
		(property "Reference" "R999"
			(at 0 0 0)
			(layer "B.SilkS")
			(hide yes)
			(effects
				(font
					(size 1.27 1.27)
				)
				(justify mirror)
			)
		)
		(property "Value" ""
			(at 0 0 0)
			(layer "B.Fab")
			(effects
				(font
					(size 1.27 1.27)
				)
				(justify mirror)
			)
		)
		(duplicate_pad_numbers_are_jumpers no)
		(fp_line
			(start 0.7874 0.4064)
			(end 0.7874 -0.4064)
			(stroke
				(width 0.1524)
				(type default)
			)
			(layer "B.SilkS")
		)
		(fp_line
			(start 0.7874 -0.4064)
			(end -0.7874 -0.4064)
			(stroke
				(width 0.1524)
				(type default)
			)
			(layer "B.SilkS")
		)
		(fp_line
			(start -0.7874 0.4064)
			(end 0.7874 0.4064)
			(stroke
				(width 0.1524)
				(type default)
			)
			(layer "B.SilkS")
		)
		(fp_line
			(start -0.7874 -0.4064)
			(end -0.7874 0.4064)
			(stroke
				(width 0.1524)
				(type default)
			)
			(layer "B.SilkS")
		)
		(fp_line
			(start 0.67945 0.3048)
			(end 0.67945 -0.305054)
			(stroke
				(width 0.1)
				(type default)
			)
			(layer "B.Fab")
		)
		(fp_line
			(start 0.67945 -0.305054)
			(end 0.12065 -0.305054)
			(stroke
				(width 0.1)
				(type default)
			)
			(layer "B.Fab")
		)
		(fp_line
			(start 0.12065 0.3048)
			(end 0.67945 0.3048)
			(stroke
				(width 0.1)
				(type default)
			)
			(layer "B.Fab")
		)
		(fp_line
			(start 0.12065 0.2794)
			(end 0.12065 0.3048)
			(stroke
				(width 0.1)
				(type default)
			)
			(layer "B.Fab")
		)
		(fp_line
			(start 0.12065 -0.2794)
			(end -0.12065 -0.2794)
			(stroke
				(width 0.1)
				(type default)
			)
			(layer "B.Fab")
		)
		(fp_line
			(start 0.12065 -0.305054)
			(end 0.12065 -0.2794)
			(stroke
				(width 0.1)
				(type default)
			)
			(layer "B.Fab")
		)
		(fp_line
			(start -0.120396 0.3048)
			(end -0.120396 0.2794)
			(stroke
				(width 0.1)
				(type default)
			)
			(layer "B.Fab")
		)
		(fp_line
			(start -0.120396 0.2794)
			(end 0.12065 0.2794)
			(stroke
				(width 0.1)
				(type default)
			)
			(layer "B.Fab")
		)
		(fp_line
			(start -0.12065 -0.2794)
			(end -0.12065 -0.3048)
			(stroke
				(width 0.1)
				(type default)
			)
			(layer "B.Fab")
		)
		(fp_line
			(start -0.12065 -0.3048)
			(end -0.67945 -0.3048)
			(stroke
				(width 0.1)
				(type default)
			)
			(layer "B.Fab")
		)
		(fp_line
			(start -0.67945 0.3048)
			(end -0.120396 0.3048)
			(stroke
				(width 0.1)
				(type default)
			)
			(layer "B.Fab")
		)
		(fp_line
			(start -0.67945 -0.3048)
			(end -0.67945 0.3048)
			(stroke
				(width 0.1)
				(type default)
			)
			(layer "B.Fab")
		)
		(pad "1" smd circle
			(at 0.40005 0)
			(size 0 0)
			(layers "B.Cu" "B.Mask" "B.Paste")
			(net "UART_PEX3_CLI_BUF_R_TX")
		)
		(pad "2" smd circle
			(at -0.40005 0)
			(size 0 0)
			(layers "B.Cu" "B.Mask" "B.Paste")
			(net "UART_PEX3_CLI_BUF_TX")
		)
	)
)
